(kicad_pcb
	(version 20211014)
	(generator pcbnew)
	(general
    (thickness 1.6)
  )
	(paper "A4")
	(title_block
    (title "SA800U (Snapdragon 845) Baseboard")
    (date "2023-10-19")
    (rev "1.0.3")
    (company "Antmicro Ltd.")
    (comment 1 "www.antmicro.com")
		(comment 9 "footprints 351-357 of 589")
	)
	(layers
    (0 "F.Cu" signal)
    (1 "In1.Cu" power)
    (2 "In2.Cu" signal)
    (3 "In3.Cu" signal)
    (4 "In4.Cu" power)
    (31 "B.Cu" signal)
    (32 "B.Adhes" user "B.Adhesive")
    (33 "F.Adhes" user "F.Adhesive")
    (34 "B.Paste" user)
    (35 "F.Paste" user)
    (36 "B.SilkS" user "B.Silkscreen")
    (37 "F.SilkS" user "F.Silkscreen")
    (38 "B.Mask" user)
    (39 "F.Mask" user)
    (40 "Dwgs.User" user "User.Drawings")
    (41 "Cmts.User" user "User.Comments")
    (42 "Eco1.User" user "User.Eco1")
    (43 "Eco2.User" user "User.Eco2")
    (44 "Edge.Cuts" user)
    (45 "Margin" user)
    (46 "B.CrtYd" user "B.Courtyard")
    (47 "F.CrtYd" user "F.Courtyard")
    (48 "B.Fab" user)
    (49 "F.Fab" user)
  )
	(footprint "sa800u-baseboard-hw-footprints:C_0402_1005Metric" (layer "B.Cu")
    (tedit 616D63CF)
    (at 143.2 131.95)
    (descr "Capacitor SMD 0402")
    (tags "capacitor SMD 0402")
    (property "Author" "Antmicro")
    (property "DNP" "DNP")
    (property "Dielectric" "")
    (property "License" "Apache-2.0")
    (property "MPN" "CC0402MRX5R5BB106")
    (property "Manufacturer" "Yaego")
    (property "Sheetfile" "hdmi-converter.kicad_sch")
    (property "Sheetname" "HDMI converter")
    (property "Val" "10u")
    (property "Voltage" "")
    (attr exclude_from_pos_files)
    (fp_text reference "C36" (at 3.02 0.4 180) (layer "B.SilkS")
      (effects (font (size 0.7 0.7) (thickness 0.15)) (justify left bottom mirror))
    )
    (fp_text value "C_10u_0402" (at 0 -1.4 180) (layer "B.Fab")
      (effects (font (size 0.7 0.7) (thickness 0.15)) (justify left bottom mirror))
    )
    (fp_text user "Author: Antmicro" (at -0.932 -4.17 180) (layer "B.Fab") hide
      (effects (font (size 0.7 0.7) (thickness 0.15)) (justify left bottom mirror))
    )
    (fp_text user "License: Apache-2.0" (at -0.932 -5.17 180) (layer "B.Fab") hide
      (effects (font (size 0.7 0.7) (thickness 0.15)) (justify left bottom mirror))
    )
    (fp_text user "${REFERENCE}" (at -0.932 -3.168 180) (layer "B.Fab") hide
      (effects (font (size 0.7 0.7) (thickness 0.15)) (justify left bottom mirror))
    )
    (fp_rect (start -0.94 0.47) (end 0.94 -0.47) (layer "B.CrtYd") (width 0.05) (fill none))
    (fp_rect (start -0.499 0.249) (end 0.499 -0.249) (layer "B.Fab") (width 0.15) (fill none))
    (pad "1" smd roundrect (at -0.484 0) (size 0.59 0.64) (layers "B.Cu" "B.Paste" "B.Mask") (roundrect_rratio 0.25)
      (net 191 "/HDMI converter/LT9611_VCC12_TX") (pintype "passive"))
    (pad "2" smd roundrect (at 0.484 0) (size 0.59 0.64) (layers "B.Cu" "B.Paste" "B.Mask") (roundrect_rratio 0.25)
      (net 1 "GND") (pintype "passive"))
  )
	(footprint "sa800u-baseboard-hw-footprints:C_0402_1005Metric" (layer "B.Cu")
    (tedit 616D63CF)
    (at 142.65 128.7 90)
    (descr "Capacitor SMD 0402")
    (tags "capacitor SMD 0402")
    (property "Author" "Antmicro")
    (property "Dielectric" "X5R")
    (property "License" "Apache-2.0")
    (property "MPN" "GRM155R61H104KE14D")
    (property "Manufacturer" "Murata")
    (property "Sheetfile" "hdmi-converter.kicad_sch")
    (property "Sheetname" "HDMI converter")
    (property "Val" "100n")
    (property "Voltage" "50V")
    (attr smd)
    (fp_text reference "C39" (at 0.93 1.04) (layer "B.SilkS")
      (effects (font (size 0.7 0.7) (thickness 0.15)) (justify left bottom mirror))
    )
    (fp_text value "C_100n_0402" (at 0 -1.4 270) (layer "B.Fab")
      (effects (font (size 0.7 0.7) (thickness 0.15)) (justify left bottom mirror))
    )
    (fp_text user "License: Apache-2.0" (at -0.932 -5.17 270) (layer "B.Fab") hide
      (effects (font (size 0.7 0.7) (thickness 0.15)) (justify left bottom mirror))
    )
    (fp_text user "${REFERENCE}" (at -0.932 -3.168 270) (layer "B.Fab") hide
      (effects (font (size 0.7 0.7) (thickness 0.15)) (justify left bottom mirror))
    )
    (fp_text user "Author: Antmicro" (at -0.932 -4.17 270) (layer "B.Fab") hide
      (effects (font (size 0.7 0.7) (thickness 0.15)) (justify left bottom mirror))
    )
    (fp_rect (start -0.94 0.47) (end 0.94 -0.47) (layer "B.CrtYd") (width 0.05) (fill none))
    (fp_rect (start -0.499 0.249) (end 0.499 -0.249) (layer "B.Fab") (width 0.15) (fill none))
    (pad "1" smd roundrect (at -0.484 0 90) (size 0.59 0.64) (layers "B.Cu" "B.Paste" "B.Mask") (roundrect_rratio 0.25)
      (net 191 "/HDMI converter/LT9611_VCC12_TX") (pintype "passive"))
    (pad "2" smd roundrect (at 0.484 0 90) (size 0.59 0.64) (layers "B.Cu" "B.Paste" "B.Mask") (roundrect_rratio 0.25)
      (net 1 "GND") (pintype "passive"))
  )
	(footprint "sa800u-baseboard-hw-footprints:L_0603_1608Metric" (layer "B.Cu")
    (tedit 5D5D3F54)
    (at 140.25 130.65)
    (property "Author" "Antmicro")
    (property "IMax" "")
    (property "ISat" "")
    (property "License" "Apache-2.0")
    (property "MPN" "BRC1608TR35M")
    (property "Manufacturer" "Taiyo Yuden")
    (property "Sheetfile" "hdmi-converter.kicad_sch")
    (property "Sheetname" "HDMI converter")
    (property "Size" "")
    (property "Val" "350n/1.4A")
    (attr smd)
    (fp_text reference "L3" (at -1.1 0.45 180) (layer "B.SilkS")
      (effects (font (size 0.7 0.7) (thickness 0.15)) (justify left bottom mirror))
    )
    (fp_text value "L_350n_1.4A_0603" (at 0 -2 180) (layer "B.Fab")
      (effects (font (size 0.7 0.7) (thickness 0.15)) (justify left bottom mirror))
    )
    (fp_text user "${REFERENCE}" (at -1.9 -3.1 180) (layer "B.Fab") hide
      (effects (font (size 0.7 0.7) (thickness 0.15)) (justify left bottom mirror))
    )
    (fp_text user "License: Apache-2.0" (at -1.9 -5.75 180) (layer "B.Fab") hide
      (effects (font (size 0.7 0.7) (thickness 0.15)) (justify left bottom mirror))
    )
    (fp_text user "Author: Antmicro" (at -1.9 -4.4 180) (layer "B.Fab") hide
      (effects (font (size 0.7 0.7) (thickness 0.15)) (justify left bottom mirror))
    )
    (fp_line (start -0.25 0.45) (end 0.25 0.45) (layer "B.SilkS") (width 0.1))
    (fp_line (start -0.25 -0.45) (end 0.25 -0.45) (layer "B.SilkS") (width 0.1))
    (fp_rect (start -1.15 0.75) (end 1.15 -0.75) (layer "B.CrtYd") (width 0.05) (fill none))
    (fp_rect (start -0.8 0.4) (end 0.8 -0.4) (layer "B.Fab") (width 0.1) (fill none))
    (pad "1" smd roundrect (at -0.625 0) (size 0.55 1) (layers "B.Cu" "B.Paste" "B.Mask") (roundrect_rratio 0.15)
      (net 131 "3V3_SYS") (pintype "passive"))
    (pad "2" smd roundrect (at 0.625 0) (size 0.55 1) (layers "B.Cu" "B.Paste" "B.Mask") (roundrect_rratio 0.15)
      (net 187 "/HDMI converter/LT9611_VCC33_TX") (pintype "passive"))
  )
	(footprint "sa800u-baseboard-hw-footprints:L_0603_1608Metric" (layer "B.Cu")
    (tedit 5D5D3F54)
    (at 143.8 130.65 180)
    (property "Author" "Antmicro")
    (property "IMax" "")
    (property "ISat" "")
    (property "License" "Apache-2.0")
    (property "MPN" "BRC1608TR35M")
    (property "Manufacturer" "Taiyo Yuden")
    (property "Sheetfile" "hdmi-converter.kicad_sch")
    (property "Sheetname" "HDMI converter")
    (property "Size" "")
    (property "Val" "350n/1.4A")
    (attr smd)
    (fp_text reference "L6" (at -2.53 -0.52) (layer "B.SilkS")
      (effects (font (size 0.7 0.7) (thickness 0.15)) (justify left bottom mirror))
    )
    (fp_text value "L_350n_1.4A_0603" (at 0 -2) (layer "B.Fab")
      (effects (font (size 0.7 0.7) (thickness 0.15)) (justify left bottom mirror))
    )
    (fp_text user "${REFERENCE}" (at -1.9 -3.1) (layer "B.Fab") hide
      (effects (font (size 0.7 0.7) (thickness 0.15)) (justify left bottom mirror))
    )
    (fp_text user "License: Apache-2.0" (at -1.9 -5.75) (layer "B.Fab") hide
      (effects (font (size 0.7 0.7) (thickness 0.15)) (justify left bottom mirror))
    )
    (fp_text user "Author: Antmicro" (at -1.9 -4.4) (layer "B.Fab") hide
      (effects (font (size 0.7 0.7) (thickness 0.15)) (justify left bottom mirror))
    )
    (fp_line (start -0.25 -0.45) (end 0.25 -0.45) (layer "B.SilkS") (width 0.1))
    (fp_line (start -0.25 0.45) (end 0.25 0.45) (layer "B.SilkS") (width 0.1))
    (fp_rect (start -1.15 0.75) (end 1.15 -0.75) (layer "B.CrtYd") (width 0.05) (fill none))
    (fp_rect (start -0.8 0.4) (end 0.8 -0.4) (layer "B.Fab") (width 0.1) (fill none))
    (pad "1" smd roundrect (at -0.625 0 180) (size 0.55 1) (layers "B.Cu" "B.Paste" "B.Mask") (roundrect_rratio 0.15)
      (net 138 "1V2_SYS") (pintype "passive"))
    (pad "2" smd roundrect (at 0.625 0 180) (size 0.55 1) (layers "B.Cu" "B.Paste" "B.Mask") (roundrect_rratio 0.15)
      (net 191 "/HDMI converter/LT9611_VCC12_TX") (pintype "passive"))
  )
	(footprint "sa800u-baseboard-hw-footprints:R_0402_1005Metric" (layer "B.Cu")
    (tedit 5FD9C158)
    (at 144.1 128.15 180)
    (descr "Resistor SMD 0402")
    (tags "resistor SMD 0402")
    (property "Author" "Antmicro")
    (property "License" "Apache-2.0")
    (property "MPN" "CR0402-FX-7681GLF")
    (property "Manufacturer" "Bourns")
    (property "Sheetfile" "hdmi-converter.kicad_sch")
    (property "Sheetname" "HDMI converter")
    (property "Tolerance" "1%")
    (property "Val" "7k68")
    (attr smd)
    (fp_text reference "R22" (at -3.12 -0.3) (layer "B.SilkS")
      (effects (font (size 0.7 0.7) (thickness 0.15)) (justify left bottom mirror))
    )
    (fp_text value "R_7k68_0402" (at 0 -1.4) (layer "B.Fab")
      (effects (font (size 0.7 0.7) (thickness 0.15)) (justify left bottom mirror))
    )
    (fp_text user "License: Apache-2.0" (at -0.95 -5.169) (layer "B.Fab") hide
      (effects (font (size 0.7 0.7) (thickness 0.15)) (justify left bottom mirror))
    )
    (fp_text user "Author: Antmicro" (at -0.95 -4.169) (layer "B.Fab") hide
      (effects (font (size 0.7 0.7) (thickness 0.15)) (justify left bottom mirror))
    )
    (fp_text user "${REFERENCE}" (at -0.95 -3.168) (layer "B.Fab") hide
      (effects (font (size 0.7 0.7) (thickness 0.15)) (justify left bottom mirror))
    )
    (fp_rect (start -0.93 0.47) (end 0.93 -0.47) (layer "B.CrtYd") (width 0.05) (fill none))
    (fp_rect (start -0.5 0.25) (end 0.5 -0.25) (layer "B.Fab") (width 0.15) (fill none))
    (pad "1" smd roundrect (at -0.485 0 180) (size 0.59 0.64) (layers "B.Cu" "B.Paste" "B.Mask") (roundrect_rratio 0.25)
      (net 394 "Net-(R22-Pad1)") (pintype "passive"))
    (pad "2" smd roundrect (at 0.485 0 180) (size 0.59 0.64) (layers "B.Cu" "B.Paste" "B.Mask") (roundrect_rratio 0.25)
      (net 1 "GND") (pintype "passive"))
  )
	(footprint "sa800u-baseboard-hw-footprints:R_0402_1005Metric" (layer "B.Cu")
    (tedit 5FD9C158)
    (at 154 144.75 -90)
    (descr "Resistor SMD 0402")
    (tags "resistor SMD 0402")
    (property "Author" "Antmicro")
    (property "Current" "1A")
    (property "DNP" "DNP")
    (property "License" "Apache-2.0")
    (property "MPN" "ERJ2GE0R00X")
    (property "Manufacturer" "Panasonic")
    (property "Sheetfile" "sa800u-baseboard-hw.kicad_sch")
    (property "Sheetname" "")
    (property "Tolerance" "")
    (property "Val" "0R")
    (attr exclude_from_pos_files)
    (fp_text reference "R2" (at -0.78 0.64 90) (layer "B.SilkS")
      (effects (font (size 0.7 0.7) (thickness 0.15)) (justify left bottom mirror))
    )
    (fp_text value "R_0R_0402" (at 0 -1.4 90) (layer "B.Fab")
      (effects (font (size 0.7 0.7) (thickness 0.15)) (justify left bottom mirror))
    )
    (fp_text user "${REFERENCE}" (at -0.95 -3.168 90) (layer "B.Fab") hide
      (effects (font (size 0.7 0.7) (thickness 0.15)) (justify left bottom mirror))
    )
    (fp_text user "License: Apache-2.0" (at -0.95 -5.169 90) (layer "B.Fab") hide
      (effects (font (size 0.7 0.7) (thickness 0.15)) (justify left bottom mirror))
    )
    (fp_text user "Author: Antmicro" (at -0.95 -4.169 90) (layer "B.Fab") hide
      (effects (font (size 0.7 0.7) (thickness 0.15)) (justify left bottom mirror))
    )
    (fp_rect (start -0.93 0.47) (end 0.93 -0.47) (layer "B.CrtYd") (width 0.05) (fill none))
    (fp_rect (start -0.5 0.25) (end 0.5 -0.25) (layer "B.Fab") (width 0.15) (fill none))
    (pad "1" smd roundrect (at -0.485 0 270) (size 0.59 0.64) (layers "B.Cu" "B.Paste" "B.Mask") (roundrect_rratio 0.25)
      (net 1 "GND") (pintype "passive"))
    (pad "2" smd roundrect (at 0.485 0 270) (size 0.59 0.64) (layers "B.Cu" "B.Paste" "B.Mask") (roundrect_rratio 0.25)
      (net 37 "Net-(R2-Pad2)") (pintype "passive"))
  )
	(footprint "sa800u-baseboard-hw-footprints:PowerPak-1212" (layer "B.Cu")
    (tedit 625E61BE)
    (at 81.9 136.75 180)
    (property "Author" "Antmicro")
    (property "License" "Apache-2.0")
    (property "MPN" "SI7223DN-T1-GE3")
    (property "Manufacturer" "Vishay")
    (property "Sheetfile" "psu.kicad_sch")
    (property "Sheetname" "PSU")
    (attr smd)
    (fp_text reference "Q11" (at 0 2.5) (layer "B.SilkS")
      (effects (font (size 0.65 0.65) (thickness 0.15)) (justify mirror))
    )
    (fp_text value "Si7223DN" (at 0 -3) (layer "B.Fab") hide
      (effects (font (size 0.65 0.65) (thickness 0.15)) (justify mirror))
    )
    (fp_text user "Author: Antmicro" (at -2.667 -7.4) (layer "B.Fab") hide
      (effects (font (size 0.7 0.7) (thickness 0.15)) (justify left bottom mirror))
    )
    (fp_text user "${REFERENCE}" (at 0 0) (layer "B.Fab") hide
      (effects (font (size 0.65 0.65) (thickness 0.15)) (justify mirror))
    )
    (fp_text user "License: Apache-2.0" (at -2.667 -8.599) (layer "B.Fab") hide
      (effects (font (size 0.7 0.7) (thickness 0.15)) (justify left bottom mirror))
    )
    (fp_poly (pts
        (xy 1.699 -1.178)
        (xy 1.699 -0.771)
        (xy 1.14 -0.771)
        (xy 1.14 -0.528)
        (xy 1.699 -0.528)
        (xy 1.699 -0.121)
        (xy 1.14 -0.121)
        (xy 1.14 -0.174)
        (xy -0.387 -0.174)
        (xy -0.387 -1.119)
        (xy -0.386607 -1.698508)
        (xy -0.047 -1.699)
        (xy -0.047 -1.119)
        (xy 1.14 -1.119)
        (xy 1.14 -1.178)
      ) (layer "B.Paste") (width 0.1) (fill solid))
    (fp_poly (pts
        (xy 1.699 0.122)
        (xy 1.699 0.529)
        (xy 1.14 0.529)
        (xy 1.14 0.772)
        (xy 1.699 0.772)
        (xy 1.699 1.179)
        (xy 1.14 1.179)
        (xy 1.14 1.12)
        (xy -0.047 1.12)
        (xy -0.047 1.7)
        (xy -0.387 1.7)
        (xy -0.387 1.12)
        (xy -0.386607 0.174507)
        (xy 1.14 0.175)
        (xy 1.14 0.122)
      ) (layer "B.Paste") (width 0.1) (fill solid))
    (fp_line (start 1.701 1.702) (end 1.701 1.511) (layer "B.SilkS") (width 0.15))
    (fp_line (start 1.701 -1.701) (end 0.2 -1.7) (layer "B.SilkS") (width 0.15))
    (fp_line (start -0.6 -1.7) (end -1.702 -1.701) (layer "B.SilkS") (width 0.15))
    (fp_line (start 0.2 1.702) (end 1.701 1.702) (layer "B.SilkS") (width 0.15))
    (fp_line (start -1.702 -1.701) (end -1.702 -1.51) (layer "B.SilkS") (width 0.15))
    (fp_line (start 1.701 -1.51) (end 1.701 -1.701) (layer "B.SilkS") (width 0.15))
    (fp_line (start -1.702 1.702) (end -0.6 1.7) (layer "B.SilkS") (width 0.15))
    (fp_line (start -1.702 1.511) (end -1.702 1.702) (layer "B.SilkS") (width 0.15))
    (fp_circle (center -1.85 1.3) (end -1.8 1.3) (layer "B.SilkS") (width 0.15) (fill solid))
    (fp_poly (pts
        (xy 1.699 1.179)
        (xy 1.14 1.179)
        (xy 1.14 1.12)
        (xy -0.047 1.12)
        (xy -0.047 1.7)
        (xy -0.387 1.7)
        (xy -0.387 0.175)
        (xy 1.14 0.175)
        (xy 1.14 0.122)
        (xy 1.699 0.122)
        (xy 1.699 0.529)
        (xy 1.14 0.529)
        (xy 1.14 0.772)
        (xy 1.699 0.772)
      ) (layer "B.Mask") (width 0.1) (fill solid))
    (fp_poly (pts
        (xy -0.387 -0.174)
        (xy -0.387 -1.699)
        (xy -0.047 -1.699)
        (xy -0.047 -1.119)
        (xy 1.14 -1.119)
        (xy 1.14 -1.178)
        (xy 1.699 -1.178)
        (xy 1.699 -0.771)
        (xy 1.14 -0.771)
        (xy 1.14 -0.528)
        (xy 1.699 -0.528)
        (xy 1.699 -0.121)
        (xy 1.14 -0.121)
        (xy 1.14 -0.174)
      ) (layer "B.Mask") (width 0.1) (fill solid))
    (fp_line (start 1.95 -1.95) (end -1.96 -1.95) (layer "B.CrtYd") (width 0.05))
    (fp_line (start 1.95 1.96) (end 1.95 -1.95) (layer "B.CrtYd") (width 0.05))
    (fp_line (start -1.96 1.96) (end 1.95 1.96) (layer "B.CrtYd") (width 0.05))
    (fp_line (start -1.96 -1.95) (end -1.96 1.96) (layer "B.CrtYd") (width 0.05))
    (fp_line (start -1.575 -1.574) (end -1.575 1.575) (layer "B.Fab") (width 0.15))
    (fp_line (start -1.575 1.575) (end 1.574 1.575) (layer "B.Fab") (width 0.15))
    (fp_line (start 1.574 1.575) (end 1.574 -1.574) (layer "B.Fab") (width 0.15))
    (fp_line (start 1.574 -1.574) (end -1.575 -1.574) (layer "B.Fab") (width 0.15))
    (fp_circle (center 0.99 0.975) (end 0.914 0.975) (layer "B.Fab") (width 0.15) (fill none))
    (pad "1" smd rect (at -1.446 0.975 180) (size 0.508 0.4064) (layers "B.Cu" "B.Paste" "B.Mask")
      (net 158 "/PSU/VS2") (pinfunction "S1") (pintype "passive"))
    (pad "2" smd rect (at -1.446 0.325 180) (size 0.508 0.4064) (layers "B.Cu" "B.Paste" "B.Mask")
      (net 355 "/PSU/G2") (pinfunction "G1") (pintype "passive"))
    (pad "3" smd rect (at -1.446 -0.324 180) (size 0.508 0.4064) (layers "B.Cu" "B.Paste" "B.Mask")
      (net 158 "/PSU/VS2") (pinfunction "S2") (pintype "passive"))
    (pad "4" smd rect (at -1.446 -0.974 180) (size 0.508 0.4064) (layers "B.Cu" "B.Paste" "B.Mask")
      (net 355 "/PSU/G2") (pinfunction "G2") (pintype "passive"))
    (pad "5" smd rect (at 1.42 -0.974 180) (size 0.5588 0.4064) (layers "B.Cu" "B.Paste" "B.Mask")
      (net 142 "PD_VDD") (pinfunction "D2") (pintype "passive"))
    (pad "6" smd custom (at 1.42 -0.324 180) (size 0.5588 0.4064) (layers "B.Cu" "B.Paste" "B.Mask")
      (net 142 "PD_VDD") (pinfunction "D2") (pintype "passive") (zone_connect 2)
      (options (clearance outline) (anchor rect))
      (primitives
        (gr_poly (pts
            (xy 0.2794 -0.853186)
            (xy 0.2794 -0.446786)
            (xy -0.2794 -0.446786)
            (xy -0.2794 -0.2032)
            (xy 0.2794 -0.2032)
            (xy 0.2794 0.2032)
            (xy -0.2794 0.2032)
            (xy -0.279407 0.150493)
            (xy -1.806607 0.150493)
            (xy -1.806607 -1.374508)
            (xy -1.466602 -1.374508)
            (xy -1.466602 -0.794499)
            (xy -0.279407 -0.794507)
            (xy -0.2794 -0.853186)
          ) (width 0.1) (fill yes))
      ))
    (pad "7" smd custom (at 1.42 0.325 180) (size 0.5588 0.4064) (layers "B.Cu" "B.Paste" "B.Mask")
      (net 74 "VDD") (pinfunction "D1") (pintype "passive") (zone_connect 2)
      (options (clearance outline) (anchor rect))
      (primitives
        (gr_poly (pts
            (xy 0.2794 0.446786)
            (xy 0.2794 0.853186)
            (xy -0.2794 0.853186)
            (xy -0.279407 0.794507)
            (xy -1.466602 0.794499)
            (xy -1.466602 1.374508)
            (xy -1.806607 1.374508)
            (xy -1.806607 -0.150493)
            (xy -0.279407 -0.150493)
            (xy -0.2794 -0.2032)
            (xy 0.2794 -0.2032)
            (xy 0.2794 0.2032)
            (xy -0.2794 0.2032)
            (xy -0.2794 0.446786)
          ) (width 0.1) (fill yes))
      ))
    (pad "8" smd rect (at 1.42 0.975 180) (size 0.5588 0.4064) (layers "B.Cu" "B.Paste" "B.Mask")
      (net 74 "VDD") (pinfunction "D1") (pintype "passive"))
  )
)
